# S9S_MB_2U (Grand Teton) — schematic netlist excerpt (pin names and nets, part order shuffled) for the footprints in the layout excerpt that follows; sources: Cadence DE-HDL packaged netlist, KiCad conversion of 03242023_DA0F0TMBIJ0_F0T_Motherboard_J_brd_V01_OCP.brd

R3069  Q_RES  130 1% CHIP  pkg 0402LF  page 255 : A = LED_PWRGD_SYS_PWROK_R ; B = P3V3_AUX
R3863  Q_RES  0 5% EMPTY  pkg 0402LF  page 250 : A = P12V_OCP_SFF_ISENSE_MAM_MAM ; B = P12V_OCP_SFF_ISENSE_MAM

(kicad_pcb
	(version 20260206)
	(generator "pcbnew")
	(generator_version "10.0")
	(general
		(thickness 1.6)
		(legacy_teardrops no)
	)
	(paper "A4")
	(title_block
		(title "03242023_DA0F0TMBIJ0_F0T_Motherboard_J_brd_V01_OCP.brd")
		(comment 1 "Grand Teton / footprints 3724-3725 of 6105")
	)
	(layers
		(0 "F.Cu" signal "TOP")
		(4 "In1.Cu" signal "GND")
		(6 "In2.Cu" signal "IN1")
		(8 "In3.Cu" signal "GND1")
		(10 "In4.Cu" signal "IN2")
		(12 "In5.Cu" signal "GND2")
		(14 "In6.Cu" signal "IN3")
		(16 "In7.Cu" signal "GND3")
		(18 "In8.Cu" signal "VCC")
		(20 "In9.Cu" signal "VCC1")
		(22 "In10.Cu" signal "GND4")
		(24 "In11.Cu" signal "IN4")
		(26 "In12.Cu" signal "GND5")
		(28 "In13.Cu" signal "IN5")
		(30 "In14.Cu" signal "GND6")
		(32 "In15.Cu" signal "IN6")
		(34 "In16.Cu" signal "GND7")
		(2 "B.Cu" signal "BOTTOM")
		(9 "F.Adhes" user "F.Adhesive")
		(11 "B.Adhes" user "B.Adhesive")
		(13 "F.Paste" user "Package Geometry/Pastemask Top")
		(15 "B.Paste" user "Package Geometry/Pastemask Bottom")
		(5 "F.SilkS" user "Ref Des/Silkscreen Top")
		(7 "B.SilkS" user "Ref Des/Silkscreen Bottom")
		(1 "F.Mask" user "Board Geometry/Soldermask Top")
		(3 "B.Mask" user "Board Geometry/Soldermask Bottom")
		(17 "Dwgs.User" user "User.Drawings")
		(19 "Cmts.User" user "User.Comments")
		(21 "Eco1.User" user "User.Eco1")
		(23 "Eco2.User" user "User.Eco2")
		(25 "Edge.Cuts" user "Board Geometry/Outline")
		(27 "Margin" user)
		(31 "F.CrtYd" user "Package Geometry/Place Bound Top")
		(29 "B.CrtYd" user "Package Geometry/Place Bound Bottom")
		(35 "F.Fab" user "Ref Des/Assembly Top")
		(33 "B.Fab" user "Ref Des/Assembly Bottom")
	)
	(footprint ""
		(layer "F.Cu")
		(at 28.532328 -99.586034)
		(property "Reference" "R3863"
			(at 0 0 0)
			(layer "F.SilkS")
			(hide yes)
			(effects
				(font
					(size 1.27 1.27)
				)
			)
		)
		(property "Value" ""
			(at 0 0 0)
			(layer "F.Fab")
			(effects
				(font
					(size 1.27 1.27)
				)
			)
		)
		(duplicate_pad_numbers_are_jumpers no)
		(fp_line
			(start -0.7874 -0.4064)
			(end 0.7874 -0.4064)
			(stroke
				(width 0.1524)
				(type default)
			)
			(layer "F.SilkS")
		)
		(fp_line
			(start -0.7874 0.4064)
			(end -0.7874 -0.4064)
			(stroke
				(width 0.1524)
				(type default)
			)
			(layer "F.SilkS")
		)
		(fp_line
			(start 0.7874 -0.4064)
			(end 0.7874 0.4064)
			(stroke
				(width 0.1524)
				(type default)
			)
			(layer "F.SilkS")
		)
		(fp_line
			(start 0.7874 0.4064)
			(end -0.7874 0.4064)
			(stroke
				(width 0.1524)
				(type default)
			)
			(layer "F.SilkS")
		)
		(fp_line
			(start -0.67945 -0.305054)
			(end -0.12065 -0.305054)
			(stroke
				(width 0.1)
				(type default)
			)
			(layer "F.Fab")
		)
		(fp_line
			(start -0.67945 0.3048)
			(end -0.67945 -0.305054)
			(stroke
				(width 0.1)
				(type default)
			)
			(layer "F.Fab")
		)
		(fp_line
			(start -0.12065 -0.305054)
			(end -0.12065 -0.2794)
			(stroke
				(width 0.1)
				(type default)
			)
			(layer "F.Fab")
		)
		(fp_line
			(start -0.12065 -0.2794)
			(end 0.12065 -0.2794)
			(stroke
				(width 0.1)
				(type default)
			)
			(layer "F.Fab")
		)
		(fp_line
			(start -0.12065 0.2794)
			(end -0.12065 0.3048)
			(stroke
				(width 0.1)
				(type default)
			)
			(layer "F.Fab")
		)
		(fp_line
			(start -0.12065 0.3048)
			(end -0.67945 0.3048)
			(stroke
				(width 0.1)
				(type default)
			)
			(layer "F.Fab")
		)
		(fp_line
			(start 0.120396 0.2794)
			(end -0.12065 0.2794)
			(stroke
				(width 0.1)
				(type default)
			)
			(layer "F.Fab")
		)
		(fp_line
			(start 0.120396 0.3048)
			(end 0.120396 0.2794)
			(stroke
				(width 0.1)
				(type default)
			)
			(layer "F.Fab")
		)
		(fp_line
			(start 0.12065 -0.3048)
			(end 0.67945 -0.3048)
			(stroke
				(width 0.1)
				(type default)
			)
			(layer "F.Fab")
		)
		(fp_line
			(start 0.12065 -0.2794)
			(end 0.12065 -0.3048)
			(stroke
				(width 0.1)
				(type default)
			)
			(layer "F.Fab")
		)
		(fp_line
			(start 0.67945 -0.3048)
			(end 0.67945 0.3048)
			(stroke
				(width 0.1)
				(type default)
			)
			(layer "F.Fab")
		)
		(fp_line
			(start 0.67945 0.3048)
			(end 0.120396 0.3048)
			(stroke
				(width 0.1)
				(type default)
			)
			(layer "F.Fab")
		)
		(pad "1" smd rect
			(at -0.40005 0 180)
			(size 0.4572 0.508)
			(layers "F.Cu" "F.Mask" "F.Paste")
			(net "P12V_OCP_SFF_ISENSE_MAM_MAM")
		)
		(pad "2" smd rect
			(at 0.40005 0 180)
			(size 0.4572 0.508)
			(layers "F.Cu" "F.Mask" "F.Paste")
			(net "P12V_OCP_SFF_ISENSE_MAM")
		)
	)
	(footprint ""
		(layer "F.Cu")
		(at 90.086688 -65.193672 -90)
		(property "Reference" "R3069"
			(at 0 0 270)
			(layer "F.SilkS")
			(hide yes)
			(effects
				(font
					(size 1.27 1.27)
				)
			)
		)
		(property "Value" ""
			(at 0 0 270)
			(layer "F.Fab")
			(effects
				(font
					(size 1.27 1.27)
				)
			)
		)
		(duplicate_pad_numbers_are_jumpers no)
		(fp_line
			(start -0.7874 0.4064)
			(end -0.7874 -0.4064)
			(stroke
				(width 0.1524)
				(type default)
			)
			(layer "F.SilkS")
		)
		(fp_line
			(start 0.7874 0.4064)
			(end -0.7874 0.4064)
			(stroke
				(width 0.1524)
				(type default)
			)
			(layer "F.SilkS")
		)
		(fp_line
			(start -0.7874 -0.4064)
			(end 0.7874 -0.4064)
			(stroke
				(width 0.1524)
				(type default)
			)
			(layer "F.SilkS")
		)
		(fp_line
			(start 0.7874 -0.4064)
			(end 0.7874 0.4064)
			(stroke
				(width 0.1524)
				(type default)
			)
			(layer "F.SilkS")
		)
		(fp_line
			(start -0.67945 0.3048)
			(end -0.67945 -0.305054)
			(stroke
				(width 0.1)
				(type default)
			)
			(layer "F.Fab")
		)
		(fp_line
			(start -0.12065 0.3048)
			(end -0.67945 0.3048)
			(stroke
				(width 0.1)
				(type default)
			)
			(layer "F.Fab")
		)
		(fp_line
			(start 0.120396 0.3048)
			(end 0.120396 0.2794)
			(stroke
				(width 0.1)
				(type default)
			)
			(layer "F.Fab")
		)
		(fp_line
			(start 0.67945 0.3048)
			(end 0.120396 0.3048)
			(stroke
				(width 0.1)
				(type default)
			)
			(layer "F.Fab")
		)
		(fp_line
			(start -0.12065 0.2794)
			(end -0.12065 0.3048)
			(stroke
				(width 0.1)
				(type default)
			)
			(layer "F.Fab")
		)
		(fp_line
			(start 0.120396 0.2794)
			(end -0.12065 0.2794)
			(stroke
				(width 0.1)
				(type default)
			)
			(layer "F.Fab")
		)
		(fp_line
			(start -0.12065 -0.2794)
			(end 0.12065 -0.2794)
			(stroke
				(width 0.1)
				(type default)
			)
			(layer "F.Fab")
		)
		(fp_line
			(start 0.12065 -0.2794)
			(end 0.12065 -0.3048)
			(stroke
				(width 0.1)
				(type default)
			)
			(layer "F.Fab")
		)
		(fp_line
			(start 0.12065 -0.3048)
			(end 0.67945 -0.3048)
			(stroke
				(width 0.1)
				(type default)
			)
			(layer "F.Fab")
		)
		(fp_line
			(start 0.67945 -0.3048)
			(end 0.67945 0.3048)
			(stroke
				(width 0.1)
				(type default)
			)
			(layer "F.Fab")
		)
		(fp_line
			(start -0.67945 -0.305054)
			(end -0.12065 -0.305054)
			(stroke
				(width 0.1)
				(type default)
			)
			(layer "F.Fab")
		)
		(fp_line
			(start -0.12065 -0.305054)
			(end -0.12065 -0.2794)
			(stroke
				(width 0.1)
				(type default)
			)
			(layer "F.Fab")
		)
		(pad "1" smd circle
			(at -0.40005 0 270)
			(size 0 0)
			(layers "F.Cu" "F.Mask" "F.Paste")
			(net "LED_PWRGD_SYS_PWROK_R")
		)
		(pad "2" smd circle
			(at 0.40005 0 270)
			(size 0 0)
			(layers "F.Cu" "F.Mask" "F.Paste")
			(net "P3V3_AUX")
		)
	)
)
